(kicad_pcb
	(version 20241229)
	(generator "pcbnew")
	(generator_version "9.0")
	(general
		(thickness 1.61)
		(legacy_teardrops no)
	)
	(paper "A3")
	(title_block
		(title "RDIMM DDR5 Tester")
		(date "2026-05-21")
		(rev "2.2.0")
		(company "Antmicro")
		(comment 9 "footprints 760-764 of 796")
	)
	(layers
		(0 "F.Cu" signal)
		(4 "In1.Cu" power)
		(6 "In2.Cu" mixed)
		(8 "In3.Cu" power)
		(10 "In4.Cu" mixed)
		(12 "In5.Cu" power)
		(14 "In6.Cu" mixed)
		(16 "In7.Cu" power)
		(18 "In8.Cu" power)
		(20 "In9.Cu" mixed)
		(22 "In10.Cu" power)
		(2 "B.Cu" signal)
		(9 "F.Adhes" user "F.Adhesive")
		(11 "B.Adhes" user "B.Adhesive")
		(13 "F.Paste" user)
		(15 "B.Paste" user)
		(5 "F.SilkS" user "F.Silkscreen")
		(7 "B.SilkS" user "B.Silkscreen")
		(1 "F.Mask" user)
		(3 "B.Mask" user)
		(17 "Dwgs.User" user "User.Drawings")
		(19 "Cmts.User" user "User.Comments")
		(21 "Eco1.User" user "User.Eco1")
		(23 "Eco2.User" user "User.Eco2")
		(25 "Edge.Cuts" user)
		(27 "Margin" user)
		(31 "F.CrtYd" user "F.Courtyard")
		(29 "B.CrtYd" user "B.Courtyard")
		(35 "F.Fab" user)
		(33 "B.Fab" user)
	)
	(footprint "antmicro-footprints:R_0402_1005Metric"
		(layer "B.Cu")
		(at 238.424499 188.849 180)
		(descr "Resistor SMD 0402")
		(tags "resistor SMD 0402")
		(property "Reference" "R174"
			(at -3.95 -0.5 0)
			(layer "B.SilkS")
			(effects
				(font
					(size 0.7 0.7)
					(thickness 0.15)
				)
				(justify left bottom mirror)
			)
		)
		(property "Value" "R_0R_0402"
			(at -1.011843 -1.772047 0)
			(layer "B.Fab")
			(effects
				(font
					(size 0.7 0.7)
					(thickness 0.15)
				)
				(justify left bottom mirror)
			)
		)
		(property "Datasheet" "https://industrial.panasonic.com/cdbs/www-data/pdf/RDA0000/AOA0000C301.pdf"
			(at 0 0 180)
			(layer "F.Fab")
			(hide yes)
			(effects
				(font
					(size 1.27 1.27)
					(thickness 0.15)
				)
			)
		)
		(property "Manufacturer" "Panasonic"
			(at 0 0 180)
			(unlocked yes)
			(layer "B.Fab")
			(hide yes)
			(effects
				(font
					(size 1 1)
					(thickness 0.15)
				)
				(justify mirror)
			)
		)
		(property "MPN" "ERJ2GE0R00X"
			(at 0 0 180)
			(unlocked yes)
			(layer "B.Fab")
			(hide yes)
			(effects
				(font
					(size 1 1)
					(thickness 0.15)
				)
				(justify mirror)
			)
		)
		(property "Val" "0R"
			(at 0 0 180)
			(unlocked yes)
			(layer "B.Fab")
			(hide yes)
			(effects
				(font
					(size 1 1)
					(thickness 0.15)
				)
				(justify mirror)
			)
		)
		(property "License" "Apache-2.0"
			(at 0 0 180)
			(unlocked yes)
			(layer "B.Fab")
			(hide yes)
			(effects
				(font
					(size 1 1)
					(thickness 0.15)
				)
				(justify mirror)
			)
		)
		(property "Author" "Antmicro"
			(at 0 0 180)
			(unlocked yes)
			(layer "B.Fab")
			(hide yes)
			(effects
				(font
					(size 1 1)
					(thickness 0.15)
				)
				(justify mirror)
			)
		)
		(property "Tolerance" "~"
			(at 0 0 180)
			(unlocked yes)
			(layer "B.Fab")
			(hide yes)
			(effects
				(font
					(size 1 1)
					(thickness 0.15)
				)
				(justify mirror)
			)
		)
		(property "Current" "1A"
			(at 0 0 180)
			(unlocked yes)
			(layer "B.Fab")
			(hide yes)
			(effects
				(font
					(size 1 1)
					(thickness 0.15)
				)
				(justify mirror)
			)
		)
		(sheetname "/I^{2}C + I3C/")
		(sheetfile "i2c.kicad_sch")
		(attr smd exclude_from_bom dnp)
		(fp_rect
			(start -0.925 0.47)
			(end 0.925 -0.47)
			(stroke
				(width 0.05)
				(type default)
			)
			(fill no)
			(layer "B.CrtYd")
		)
		(fp_rect
			(start -0.5 0.25)
			(end 0.5 -0.25)
			(stroke
				(width 0.15)
				(type solid)
			)
			(fill no)
			(layer "B.Fab")
		)
		(fp_text user "Author: Antmicro"
			(at -0.95 -4.169 0)
			(layer "B.Fab")
			(effects
				(font
					(size 0.7 0.7)
					(thickness 0.15)
				)
				(justify left bottom mirror)
			)
		)
		(fp_text user "License: Apache-2.0"
			(at -0.95 -5.169 0)
			(layer "B.Fab")
			(effects
				(font
					(size 0.7 0.7)
					(thickness 0.15)
				)
				(justify left bottom mirror)
			)
		)
		(fp_text user "${REFERENCE}"
			(at -0.95 -3.168 0)
			(layer "B.Fab")
			(effects
				(font
					(size 0.7 0.7)
					(thickness 0.15)
				)
				(justify left bottom mirror)
			)
		)
		(pad "1" smd roundrect
			(at -0.48 0 180)
			(size 0.59 0.64)
			(layers "B.Cu" "B.Mask" "B.Paste")
			(roundrect_rratio 0.25)
			(net 533 "/I^{2}C + I3C/PWR.SDA")
			(pintype "passive")
		)
		(pad "2" smd roundrect
			(at 0.48 0 180)
			(size 0.59 0.64)
			(layers "B.Cu" "B.Mask" "B.Paste")
			(roundrect_rratio 0.25)
			(net 472 "/FPGA banks HD/FPGA_DDR.SDA")
			(pintype "passive")
		)
	)
	(footprint "antmicro-footprints:R_0402_1005Metric"
		(layer "B.Cu")
		(at 188.4 105.5 180)
		(descr "Resistor SMD 0402")
		(tags "resistor SMD 0402")
		(property "Reference" "R27"
			(at -3.16 0.81 0)
			(layer "B.SilkS")
			(effects
				(font
					(size 0.7 0.7)
					(thickness 0.15)
				)
				(justify left bottom mirror)
			)
		)
		(property "Value" "R_0R_0402"
			(at -1.011843 -1.772047 0)
			(layer "B.Fab")
			(effects
				(font
					(size 0.7 0.7)
					(thickness 0.15)
				)
				(justify left bottom mirror)
			)
		)
		(property "Datasheet" "https://industrial.panasonic.com/cdbs/www-data/pdf/RDA0000/AOA0000C301.pdf"
			(at 0 0 180)
			(layer "F.Fab")
			(hide yes)
			(effects
				(font
					(size 1.27 1.27)
					(thickness 0.15)
				)
			)
		)
		(property "MPN" "ERJ2GE0R00X"
			(at 0 0 180)
			(unlocked yes)
			(layer "B.Fab")
			(hide yes)
			(effects
				(font
					(size 1 1)
					(thickness 0.15)
				)
				(justify mirror)
			)
		)
		(property "Manufacturer" "Panasonic"
			(at 0 0 180)
			(unlocked yes)
			(layer "B.Fab")
			(hide yes)
			(effects
				(font
					(size 1 1)
					(thickness 0.15)
				)
				(justify mirror)
			)
		)
		(property "License" "Apache-2.0"
			(at 0 0 180)
			(unlocked yes)
			(layer "B.Fab")
			(hide yes)
			(effects
				(font
					(size 1 1)
					(thickness 0.15)
				)
				(justify mirror)
			)
		)
		(property "Author" "Antmicro"
			(at 0 0 180)
			(unlocked yes)
			(layer "B.Fab")
			(hide yes)
			(effects
				(font
					(size 1 1)
					(thickness 0.15)
				)
				(justify mirror)
			)
		)
		(property "Val" "0R"
			(at 0 0 180)
			(unlocked yes)
			(layer "B.Fab")
			(hide yes)
			(effects
				(font
					(size 1 1)
					(thickness 0.15)
				)
				(justify mirror)
			)
		)
		(property "Tolerance" "~"
			(at 0 0 180)
			(unlocked yes)
			(layer "B.Fab")
			(hide yes)
			(effects
				(font
					(size 1 1)
					(thickness 0.15)
				)
				(justify mirror)
			)
		)
		(property "Current" "1A"
			(at 0 0 180)
			(unlocked yes)
			(layer "B.Fab")
			(hide yes)
			(effects
				(font
					(size 1 1)
					(thickness 0.15)
				)
				(justify mirror)
			)
		)
		(sheetname "/DDR5 RDIMM/")
		(sheetfile "ddr5-rdimm.kicad_sch")
		(attr smd)
		(fp_rect
			(start -0.925 0.47)
			(end 0.925 -0.47)
			(stroke
				(width 0.05)
				(type default)
			)
			(fill no)
			(layer "B.CrtYd")
		)
		(fp_rect
			(start -0.5 0.25)
			(end 0.5 -0.25)
			(stroke
				(width 0.15)
				(type solid)
			)
			(fill no)
			(layer "B.Fab")
		)
		(fp_text user "${REFERENCE}"
			(at -0.95 -3.168 0)
			(layer "B.Fab")
			(effects
				(font
					(size 0.7 0.7)
					(thickness 0.15)
				)
				(justify left bottom mirror)
			)
		)
		(fp_text user "License: Apache-2.0"
			(at -0.95 -5.169 0)
			(layer "B.Fab")
			(effects
				(font
					(size 0.7 0.7)
					(thickness 0.15)
				)
				(justify left bottom mirror)
			)
		)
		(fp_text user "Author: Antmicro"
			(at -0.95 -4.169 0)
			(layer "B.Fab")
			(effects
				(font
					(size 0.7 0.7)
					(thickness 0.15)
				)
				(justify left bottom mirror)
			)
		)
		(pad "1" smd roundrect
			(at -0.48 0 180)
			(size 0.59 0.64)
			(layers "B.Cu" "B.Mask" "B.Paste")
			(roundrect_rratio 0.25)
			(net 703 "/DDR5 RDIMM/VSS_DET1")
			(pintype "passive")
		)
		(pad "2" smd roundrect
			(at 0.48 0 180)
			(size 0.59 0.64)
			(layers "B.Cu" "B.Mask" "B.Paste")
			(roundrect_rratio 0.25)
			(net 704 "~{DDR_PRESENCE}")
			(pintype "passive")
		)
	)
	(footprint "antmicro-footprints:C_0402_1005Metric"
		(layer "B.Cu")
		(at 240.55 122.22)
		(descr "Capacitor SMD 0402")
		(tags "capacitor SMD 0402")
		(property "Reference" "C321"
			(at -1.32 2.94 0)
			(layer "B.SilkS")
			(effects
				(font
					(size 0.7 0.7)
					(thickness 0.15)
				)
				(justify right bottom mirror)
			)
		)
		(property "Value" "C_100n_0402"
			(at -1.022927 -2.155213 0)
			(layer "B.Fab")
			(effects
				(font
					(size 0.7 0.7)
					(thickness 0.15)
				)
				(justify right bottom mirror)
			)
		)
		(property "Datasheet" "https://www.murata.com/products/productdetail?partno=GRM155R61H104KE14%23"
			(at 0 0 0)
			(layer "F.Fab")
			(hide yes)
			(effects
				(font
					(size 1.27 1.27)
					(thickness 0.15)
				)
			)
		)
		(property "MPN" "GRM155R61H104KE14D"
			(at 0 0 0)
			(unlocked yes)
			(layer "B.Fab")
			(hide yes)
			(effects
				(font
					(size 1 1)
					(thickness 0.15)
				)
				(justify mirror)
			)
		)
		(property "Manufacturer" "Murata"
			(at 0 0 0)
			(unlocked yes)
			(layer "B.Fab")
			(hide yes)
			(effects
				(font
					(size 1 1)
					(thickness 0.15)
				)
				(justify mirror)
			)
		)
		(property "License" "Apache-2.0"
			(at 0 0 0)
			(unlocked yes)
			(layer "B.Fab")
			(hide yes)
			(effects
				(font
					(size 1 1)
					(thickness 0.15)
				)
				(justify mirror)
			)
		)
		(property "Author" "Antmicro"
			(at 0 0 0)
			(unlocked yes)
			(layer "B.Fab")
			(hide yes)
			(effects
				(font
					(size 1 1)
					(thickness 0.15)
				)
				(justify mirror)
			)
		)
		(property "Val" "100n"
			(at 0 0 0)
			(unlocked yes)
			(layer "B.Fab")
			(hide yes)
			(effects
				(font
					(size 1 1)
					(thickness 0.15)
				)
				(justify mirror)
			)
		)
		(property "Voltage" "50V"
			(at 0 0 0)
			(unlocked yes)
			(layer "B.Fab")
			(hide yes)
			(effects
				(font
					(size 1 1)
					(thickness 0.15)
				)
				(justify mirror)
			)
		)
		(property "Dielectric" "X5R"
			(at 0 0 0)
			(unlocked yes)
			(layer "B.Fab")
			(hide yes)
			(effects
				(font
					(size 1 1)
					(thickness 0.15)
				)
				(justify mirror)
			)
		)
		(sheetname "/Supply/")
		(sheetfile "supply.kicad_sch")
		(attr smd)
		(fp_rect
			(start -0.925 0.47)
			(end 0.925 -0.47)
			(stroke
				(width 0.05)
				(type default)
			)
			(fill no)
			(layer "B.CrtYd")
		)
		(fp_line
			(start -0.494 -0.248)
			(end -0.494 0.25)
			(stroke
				(width 0.15)
				(type solid)
			)
			(layer "B.Fab")
		)
		(fp_line
			(start -0.494 0.25)
			(end 0.504 0.25)
			(stroke
				(width 0.15)
				(type solid)
			)
			(layer "B.Fab")
		)
		(fp_line
			(start 0.504 -0.248)
			(end -0.494 -0.248)
			(stroke
				(width 0.15)
				(type solid)
			)
			(layer "B.Fab")
		)
		(fp_line
			(start 0.504 0.25)
			(end 0.504 -0.248)
			(stroke
				(width 0.15)
				(type solid)
			)
			(layer "B.Fab")
		)
		(fp_text user "License: Apache-2.0"
			(at -0.939 -5.799 180)
			(layer "B.Fab")
			(effects
				(font
					(size 0.7 0.7)
					(thickness 0.15)
				)
				(justify left bottom mirror)
			)
		)
		(fp_text user "Author: Antmicro"
			(at -0.939 -3.399 180)
			(layer "B.Fab")
			(effects
				(font
					(size 0.7 0.7)
					(thickness 0.15)
				)
				(justify left bottom mirror)
			)
		)
		(fp_text user "${REFERENCE}"
			(at -0.939 -4.599 180)
			(layer "B.Fab")
			(effects
				(font
					(size 0.7 0.7)
					(thickness 0.15)
				)
				(justify left bottom mirror)
			)
		)
		(pad "1" smd roundrect
			(at -0.48 0)
			(size 0.59 0.64)
			(layers "B.Cu" "B.Mask" "B.Paste")
			(roundrect_rratio 0.25)
			(net 1 "GND")
			(pintype "passive")
		)
		(pad "2" smd roundrect
			(at 0.48 0)
			(size 0.59 0.64)
			(layers "B.Cu" "B.Mask" "B.Paste")
			(roundrect_rratio 0.25)
			(net 811 "/Supply/heater")
			(pintype "passive")
		)
	)
	(footprint "antmicro-footprints:C_0402_1005Metric_EIA"
		(layer "B.Cu")
		(at 178 159.5 -90)
		(descr "Capacitor SMD 0402 (1005 Metric), square (rectangular) end terminal, IPC_7351 nominal, (Body size source: IPC-SM-782 page 76, https://www.pcb-3d.com/wordpress/wp-content/uploads/ipc-sm-782a_amendment_1_and_2.pdf)")
		(tags "capacitor 0402")
		(property "Reference" "C311"
			(at -0.65 -1.4 90)
			(layer "B.SilkS")
			(effects
				(font
					(size 0.7 0.7)
					(thickness 0.15)
				)
				(justify left bottom mirror)
			)
		)
		(property "Value" "C_100n_0402"
			(at 0 -1.169 90)
			(layer "B.Fab")
			(effects
				(font
					(size 0.7 0.7)
					(thickness 0.15)
				)
				(justify left bottom mirror)
			)
		)
		(property "Datasheet" "https://www.murata.com/products/productdetail?partno=GRM155R61H104KE14%23"
			(at 0 0 270)
			(layer "F.Fab")
			(hide yes)
			(effects
				(font
					(size 1.27 1.27)
					(thickness 0.15)
				)
			)
		)
		(property "MPN" "GRM155R61H104KE14D"
			(at 0 0 270)
			(unlocked yes)
			(layer "B.Fab")
			(hide yes)
			(effects
				(font
					(size 1 1)
					(thickness 0.15)
				)
				(justify mirror)
			)
		)
		(property "Manufacturer" "Murata"
			(at 0 0 270)
			(unlocked yes)
			(layer "B.Fab")
			(hide yes)
			(effects
				(font
					(size 1 1)
					(thickness 0.15)
				)
				(justify mirror)
			)
		)
		(property "License" "Apache-2.0"
			(at 0 0 270)
			(unlocked yes)
			(layer "B.Fab")
			(hide yes)
			(effects
				(font
					(size 1 1)
					(thickness 0.15)
				)
				(justify mirror)
			)
		)
		(property "Author" "Antmicro"
			(at 0 0 270)
			(unlocked yes)
			(layer "B.Fab")
			(hide yes)
			(effects
				(font
					(size 1 1)
					(thickness 0.15)
				)
				(justify mirror)
			)
		)
		(property "Val" "100n"
			(at 0 0 270)
			(unlocked yes)
			(layer "B.Fab")
			(hide yes)
			(effects
				(font
					(size 1 1)
					(thickness 0.15)
				)
				(justify mirror)
			)
		)
		(property "Voltage" "50V"
			(at 0 0 270)
			(unlocked yes)
			(layer "B.Fab")
			(hide yes)
			(effects
				(font
					(size 1 1)
					(thickness 0.15)
				)
				(justify mirror)
			)
		)
		(property "Dielectric" "X5R"
			(at 0 0 270)
			(unlocked yes)
			(layer "B.Fab")
			(hide yes)
			(effects
				(font
					(size 1 1)
					(thickness 0.15)
				)
				(justify mirror)
			)
		)
		(sheetname "/FPGA power/")
		(sheetfile "fpga-power.kicad_sch")
		(attr smd)
		(fp_rect
			(start -0.95 0.45)
			(end 0.95 -0.45)
			(stroke
				(width 0.05)
				(type default)
			)
			(fill no)
			(layer "B.CrtYd")
		)
		(fp_line
			(start -0.5 0.25)
			(end 0.498 0.25)
			(stroke
				(width 0.15)
				(type solid)
			)
			(layer "B.Fab")
		)
		(fp_line
			(start 0.498 0.25)
			(end 0.498 -0.248)
			(stroke
				(width 0.15)
				(type solid)
			)
			(layer "B.Fab")
		)
		(fp_line
			(start -0.5 -0.248)
			(end -0.5 0.25)
			(stroke
				(width 0.15)
				(type solid)
			)
			(layer "B.Fab")
		)
		(fp_line
			(start 0.498 -0.248)
			(end -0.5 -0.248)
			(stroke
				(width 0.15)
				(type solid)
			)
			(layer "B.Fab")
		)
		(fp_text user "License: Apache-2.0"
			(at -0.9656 -4.369 90)
			(layer "B.Fab")
			(effects
				(font
					(size 0.7 0.7)
					(thickness 0.15)
				)
				(justify left bottom mirror)
			)
		)
		(fp_text user "${REFERENCE}"
			(at -0.9656 -3.169 90)
			(layer "B.Fab")
			(effects
				(font
					(size 0.7 0.7)
					(thickness 0.15)
				)
				(justify left bottom mirror)
			)
		)
		(fp_text user "Author: Antmicro"
			(at -0.9656 -5.569 90)
			(layer "B.Fab")
			(effects
				(font
					(size 0.7 0.7)
					(thickness 0.15)
				)
				(justify left bottom mirror)
			)
		)
		(pad "1" smd roundrect
			(at -0.5 0 180)
			(size 0.6 0.6)
			(layers "B.Cu" "B.Mask" "B.Paste")
			(roundrect_rratio 0.25)
			(net 1 "GND")
			(pintype "passive")
		)
		(pad "2" smd roundrect
			(at 0.498 0 270)
			(size 0.6 0.6)
			(layers "B.Cu" "B.Mask" "B.Paste")
			(roundrect_rratio 0.25)
			(net 172 "+1V2_MGTAVTT")
			(pintype "passive")
		)
	)
	(footprint "antmicro-footprints:C_0402_1005Metric"
		(layer "B.Cu")
		(at 160.674499 193.224 -90)
		(descr "Capacitor SMD 0402")
		(tags "capacitor SMD 0402")
		(property "Reference" "C222"
			(at -3.774 -0.435501 90)
			(layer "B.SilkS")
			(effects
				(font
					(size 0.7 0.7)
					(thickness 0.15)
				)
				(justify left bottom mirror)
			)
		)
		(property "Value" "C_10n_0402"
			(at -1.022927 -2.155213 90)
			(layer "B.Fab")
			(effects
				(font
					(size 0.7 0.7)
					(thickness 0.15)
				)
				(justify left bottom mirror)
			)
		)
		(property "Datasheet" "https://www.murata.com/products/productdetail?partno=GRM155R71H103KA88%23"
			(at 0 0 270)
			(layer "F.Fab")
			(hide yes)
			(effects
				(font
					(size 1.27 1.27)
					(thickness 0.15)
				)
			)
		)
		(property "MPN" "GRM155R71H103KA88D"
			(at 0 0 270)
			(unlocked yes)
			(layer "B.Fab")
			(hide yes)
			(effects
				(font
					(size 1 1)
					(thickness 0.15)
				)
				(justify mirror)
			)
		)
		(property "Manufacturer" "Murata"
			(at 0 0 270)
			(unlocked yes)
			(layer "B.Fab")
			(hide yes)
			(effects
				(font
					(size 1 1)
					(thickness 0.15)
				)
				(justify mirror)
			)
		)
		(property "License" "Apache-2.0"
			(at 0 0 270)
			(unlocked yes)
			(layer "B.Fab")
			(hide yes)
			(effects
				(font
					(size 1 1)
					(thickness 0.15)
				)
				(justify mirror)
			)
		)
		(property "Author" "Antmicro"
			(at 0 0 270)
			(unlocked yes)
			(layer "B.Fab")
			(hide yes)
			(effects
				(font
					(size 1 1)
					(thickness 0.15)
				)
				(justify mirror)
			)
		)
		(property "Val" "10n"
			(at 0 0 270)
			(unlocked yes)
			(layer "B.Fab")
			(hide yes)
			(effects
				(font
					(size 1 1)
					(thickness 0.15)
				)
				(justify mirror)
			)
		)
		(property "Voltage" "50V"
			(at 0 0 270)
			(unlocked yes)
			(layer "B.Fab")
			(hide yes)
			(effects
				(font
					(size 1 1)
					(thickness 0.15)
				)
				(justify mirror)
			)
		)
		(property "Dielectric" "X7R"
			(at 0 0 270)
			(unlocked yes)
			(layer "B.Fab")
			(hide yes)
			(effects
				(font
					(size 1 1)
					(thickness 0.15)
				)
				(justify mirror)
			)
		)
		(sheetname "/FPGA MGT Interface/")
		(sheetfile "fpga-mgt.kicad_sch")
		(attr smd)
		(fp_rect
			(start -0.925 0.47)
			(end 0.925 -0.47)
			(stroke
				(width 0.05)
				(type default)
			)
			(fill no)
			(layer "B.CrtYd")
		)
		(fp_line
			(start -0.494 0.25)
			(end 0.504 0.25)
			(stroke
				(width 0.15)
				(type solid)
			)
			(layer "B.Fab")
		)
		(fp_line
			(start 0.504 0.25)
			(end 0.504 -0.248)
			(stroke
				(width 0.15)
				(type solid)
			)
			(layer "B.Fab")
		)
		(fp_line
			(start -0.494 -0.248)
			(end -0.494 0.25)
			(stroke
				(width 0.15)
				(type solid)
			)
			(layer "B.Fab")
		)
		(fp_line
			(start 0.504 -0.248)
			(end -0.494 -0.248)
			(stroke
				(width 0.15)
				(type solid)
			)
			(layer "B.Fab")
		)
		(fp_text user "License: Apache-2.0"
			(at -0.939 -5.799 90)
			(layer "B.Fab")
			(effects
				(font
					(size 0.7 0.7)
					(thickness 0.15)
				)
				(justify left bottom mirror)
			)
		)
		(fp_text user "${REFERENCE}"
			(at -0.939 -4.599 90)
			(layer "B.Fab")
			(effects
				(font
					(size 0.7 0.7)
					(thickness 0.15)
				)
				(justify left bottom mirror)
			)
		)
		(fp_text user "Author: Antmicro"
			(at -0.939 -3.399 90)
			(layer "B.Fab")
			(effects
				(font
					(size 0.7 0.7)
					(thickness 0.15)
				)
				(justify left bottom mirror)
			)
		)
		(pad "1" smd roundrect
			(at -0.48 0 270)
			(size 0.59 0.64)
			(layers "B.Cu" "B.Mask" "B.Paste")
			(roundrect_rratio 0.25)
			(net 14 "/FPGA MGT Interface/GTR_REFCLK0_N")
			(pintype "passive")
		)
		(pad "2" smd roundrect
			(at 0.48 0 270)
			(size 0.59 0.64)
			(layers "B.Cu" "B.Mask" "B.Paste")
			(roundrect_rratio 0.25)
			(net 13 "/FPGA MGT Interface/PCIE.CLK_N")
			(pintype "passive")
		)
	)
)
